FILE_TYPE = CONNECTIVITY;
{Allegro Design Entry HDL 17.2-2016 S081 (4005846) 1/11/2022}
"PAGE_NUMBER" = 135;
0"NC";
1"P3V3_AUX\g";
2"P3V3_AUX\g";
3"PVNN_TERM_CPU0\g";
4"PVNN_TERM_CPU1\g";
5"PVNN_TERM_CPU0\g";
6"PVNN_TERM_CPU1\g";
7"P3V3_AUX\g";
8"P3V3_AUX\g";
9"P3V3_AUX\g";
10"GND\g";
11"GND\g";
12"GND\g";
13"GND\g";
14"GND\g";
15"GND\g";
16"GND\g";
17"GND\g";
18"FM_CPU_EN_R"CDS_PHYS_NET_NAME"TRC_PCH_PTI1_CLK";
19"JTAG_CPU0_MUX_GTL_TDO"CDS_PHYS_NET_NAME"JTAG_DBP_CPU_QS_GTL_TMS";
20"JTAG_MUX_CPU1_GTL_TDI"CDS_PHYS_NET_NAME"JTAG_DBP_CPU_QS_GTL_TMS";
21"FM_CPU_EN"CDS_PHYS_NET_NAME"TRC_PCH_PTI1_CLK";
22"JTAG_CPU1_MUX_GTL_TDO"CDS_PHYS_NET_NAME"JTAG_DBP_CPU_QS_GTL_TMS";
23"JTAG_CPU0_MUX_GTL_TDO"CDS_PHYS_NET_NAME"JTAG_DBP_CPU_QS_GTL_TMS";
24"JTAG_MUX_CPU0_GTL_TDI"CDS_PHYS_NET_NAME"JTAG_DBP_CPU_QS_GTL_TMS";
25"JTAG_MUX_CPU1_GTL_TDI"CDS_PHYS_NET_NAME"JTAG_DBP_CPU_QS_GTL_TMS";
26"FM_CPU1_SKTOCC_N"CDS_PHYS_NET_NAME"TRC_PCH_PTI1_CLK";
27"FM_CPU0_SKTOCC_N"CDS_PHYS_NET_NAME"TRC_PCH_PTI1_CLK";
28"FM_CPU0_SKTOCC_LVT3_N"CDS_PHYS_NET_NAME"TRC_PCH_PTI1_CLK";
29"FM_CPU1_SKTOCC_LVT3_N"CDS_PHYS_NET_NAME"TRC_PCH_PTI1_CLK";
30"JTAG_MUX_QS_GTL_TDO"CDS_PHYS_NET_NAME"TRC_PCH_PTI1_CLK";
31"FM_CPU1_SKTOCC_N"CDS_PHYS_NET_NAME"TRC_PCH_PTI1_CLK";
32"JTAG_QS_MUX_GTL_TDI"CDS_PHYS_NET_NAME"TRC_PCH_PTI1_CLK";
33"FM_CPU0_SKTOCC_N"CDS_PHYS_NET_NAME"TRC_PCH_PTI1_CLK";
%"Q_CAP"
"1","(750,650)","2","pure_quanta","I100";
;
PART_NUMBER"CH4104K1B00"
VOLTAGE"25V"
TOLERANCE"10%"
VALUE"0.1UF"
MATERIAL"X7R"
PACK_TYPE"0402"
$LOCATION"C543"
CDS_LIB"pure_quanta"
CDS_LOCATION"C543"
$SEC"1"
CDS_SEC"1";
"B"
$PN"2"17;
"A"
$PN"1"9;
%"UNIVERSAL_GND"
"1","(900,-200)","0","logical_power","I103";
;
CDS_LIB"logical_power"
HDL_POWER"GND";
"A"10;
%"Q_RES"
"1","(-750,250)","0","pure_quanta","I106";
;
PART_NUMBER"CS00002JB13"
WATTAGE"1/16W"
MATERIAL"CHIP"
PACK_TYPE"0402LF"
TOLERANCE"5%"
VALUE"0"
$LOCATION"R737"
CDS_LIB"pure_quanta"
CDS_LOCATION"R737"
$SEC"1"
CDS_SEC"1";
"B"
$PN"2"26;
"A"
$PN"1"29;
%"Q_RES"
"2","(-50,500)","0","pure_quanta","I107";
;
PART_NUMBER"CS31002FB08"
VALUE"10K"
TOLERANCE"1%"
WATTAGE"1/16W"
PACK_TYPE"0402LF"
MATERIAL"CHIP"
$LOCATION"R740"
CDS_LIB"pure_quanta"
CDS_LOCATION"R740"
$SEC"1"
CDS_SEC"1";
"A"
$PN"1"1;
"B"
$PN"2"27;
%"UNIVERSAL_POWER"
"1","(-300,850)","0","logical_power","I108";
;
HDL_POWER"P3V3_AUX"
CDS_LIB"logical_power";
"A"1;
%"Q_RES"
"2","(-300,500)","0","pure_quanta","I109";
;
PART_NUMBER"CS31002FB08"
PACK_TYPE"0402LF"
VALUE"10K"
WATTAGE"1/16W"
MATERIAL"CHIP"
TOLERANCE"1%"
$LOCATION"R739"
CDS_LIB"pure_quanta"
CDS_LOCATION"R739"
$SEC"1"
CDS_SEC"1";
"A"
$PN"1"1;
"B"
$PN"2"26;
%"Q_RES"
"1","(-750,150)","0","pure_quanta","I110";
;
PART_NUMBER"CS00002JB13"
WATTAGE"1/16W"
TOLERANCE"5%"
MATERIAL"CHIP"
VALUE"0"
PACK_TYPE"0402LF"
$LOCATION"R738"
CDS_LIB"pure_quanta"
CDS_LOCATION"R738"
$SEC"1"
CDS_SEC"1";
"B"
$PN"2"27;
"A"
$PN"1"28;
%"74LVC1G66GV"
"1","(3375,250)","2","pure_quanta","I115";
;
PART_NUMBER"AL001G66000"
VALUE"74LVC1G66GV"
PART_TYPE"SMLF"
MATERIAL"IC"
LOCATION"U16"
SEC_TYPE""
CDS_LMAN_SYM_OUTLINE"-150,150,150,-150"
PIN_NAMES_ROTATE"True"
CDS_LIB"pure_quanta"
SEC"1";
"VCC"
$PN"5"8;
"E"
$PN"4"18;
"GND"
$PN"3"15;
"Z"
$PN"2"20;
"Y"
$PN"1"19;
%"UNIVERSAL_GND"
"1","(-175,3050)","0","logical_power","I27";
;
CDS_LIB"logical_power"
HDL_POWER"GND";
"A"11;
%"NC7SB3157"
"1","(-600,3550)","2","pure_quanta","I58";
;
PART_NUMBER"ALSB3157000"
MATERIAL"IC"
VALUE"NC7SB3157P6X"
MANUF_PN"NC7SB3157P6X"
$LOCATION"U21"
PACK_TYPE"SMLF"
CDS_LIB"pure_quanta"
CDS_LMAN_SYM_OUTLINE"-150,50,150,-150"
CDS_LOCATION"U21"
$SEC"1"
CDS_SEC"1";
"S"
$PN"6"33;
"B0"
$PN"3"24;
"B1"
$PN"1"25;
"VCC"
$PN"5"2;
"GND"
$PN"2"11;
"A"
$PN"4"32;
%"UNIVERSAL_POWER"
"1","(-1000,4225)","0","logical_power","I60";
;
HDL_POWER"P3V3_AUX"
CDS_LIB"logical_power";
"A"2;
%"Q_CAP"
"1","(-1150,3950)","2","pure_quanta","I61";
;
PART_NUMBER"CH5104KEB02"
VALUE"1UF"
VOLTAGE"25V"
TOLERANCE"10%"
MATERIAL"X6S"
PACK_TYPE"C0402"
$LOCATION"C541"
CDS_LIB"pure_quanta"
CDS_LOCATION"C541"
$SEC"1"
CDS_SEC"1";
"B"
$PN"2"12;
"A"
$PN"1"2;
%"Q_RES"
"2","(1250,3800)","0","pure_quanta","I65";
;
PART_NUMBER"CS11502FB07"
VALUE"150"
TOLERANCE"1%"
WATTAGE"1/16W"
PACK_TYPE"0402LF"
MATERIAL"CHIP"
$LOCATION"R743"
CDS_LIB"pure_quanta"
CDS_LOCATION"R743"
$SEC"1"
CDS_SEC"1";
"A"
$PN"1"4;
"B"
$PN"2"25;
%"Q_RES"
"2","(600,3800)","0","pure_quanta","I66";
;
PART_NUMBER"CS11502FB07"
VALUE"150"
WATTAGE"1/16W"
PACK_TYPE"0402LF"
TOLERANCE"1%"
MATERIAL"CHIP"
$LOCATION"R741"
CDS_LIB"pure_quanta"
CDS_LOCATION"R741"
$SEC"1"
CDS_SEC"1";
"A"
$PN"1"3;
"B"
$PN"2"24;
%"UNIVERSAL_POWER"
"1","(600,4275)","0","logical_power","I67";
;
HDL_POWER"PVNN_TERM_CPU0"
CDS_LIB"logical_power";
"A"3;
%"UNIVERSAL_POWER"
"1","(1250,4275)","0","logical_power","I68";
;
HDL_POWER"PVNN_TERM_CPU1"
CDS_LIB"logical_power";
"A"4;
%"UNIVERSAL_GND"
"1","(-1500,3650)","0","logical_power","I69";
;
CDS_LIB"logical_power"
HDL_POWER"GND";
"A"12;
%"Q_CAP"
"1","(-1500,3950)","2","pure_quanta","I70";
;
PART_NUMBER"CH4104K1B00"
TOLERANCE"10%"
PACK_TYPE"0402"
MATERIAL"X7R"
VOLTAGE"25V"
VALUE"0.1UF"
$LOCATION"C539"
CDS_LIB"pure_quanta"
CDS_LOCATION"C539"
$SEC"1"
CDS_SEC"1";
"B"
$PN"2"12;
"A"
$PN"1"2;
%"NC7SB3157"
"1","(-600,2000)","2","pure_quanta","I71";
;
PART_NUMBER"ALSB3157000"
MATERIAL"IC"
VALUE"NC7SB3157P6X"
MANUF_PN"NC7SB3157P6X"
$LOCATION"U22"
CDS_LMAN_SYM_OUTLINE"-150,50,150,-150"
CDS_LIB"pure_quanta"
PACK_TYPE"SMLF"
CDS_LOCATION"U22"
$SEC"1"
CDS_SEC"1";
"S"
$PN"6"31;
"B0"
$PN"3"22;
"B1"
$PN"1"23;
"VCC"
$PN"5"7;
"GND"
$PN"2"13;
"A"
$PN"4"30;
%"UNIVERSAL_POWER"
"1","(1250,2725)","0","logical_power","I72";
;
HDL_POWER"PVNN_TERM_CPU0"
CDS_LIB"logical_power";
"A"5;
%"UNIVERSAL_POWER"
"1","(600,2725)","0","logical_power","I73";
;
HDL_POWER"PVNN_TERM_CPU1"
CDS_LIB"logical_power";
"A"6;
%"UNIVERSAL_POWER"
"1","(-1000,2675)","0","logical_power","I74";
;
HDL_POWER"P3V3_AUX"
CDS_LIB"logical_power";
"A"7;
%"Q_RES"
"2","(1250,2250)","0","pure_quanta","I77";
;
PART_NUMBER"CS07502FB04"
TOLERANCE"1%"
MATERIAL"CHIP"
WATTAGE"1/16W"
PACK_TYPE"0402LF"
VALUE"75"
$LOCATION"R744"
CDS_LIB"pure_quanta"
CDS_LOCATION"R744"
$SEC"1"
CDS_SEC"1";
"A"
$PN"1"5;
"B"
$PN"2"23;
%"Q_RES"
"2","(600,2250)","0","pure_quanta","I78";
;
PART_NUMBER"CS07502FB04"
TOLERANCE"1%"
VALUE"75"
WATTAGE"1/16W"
MATERIAL"CHIP"
PACK_TYPE"0402LF"
$LOCATION"R742"
CDS_LIB"pure_quanta"
CDS_LOCATION"R742"
$SEC"1"
CDS_SEC"1";
"A"
$PN"1"6;
"B"
$PN"2"22;
%"UNIVERSAL_GND"
"1","(-175,1500)","0","logical_power","I79";
;
CDS_LIB"logical_power"
HDL_POWER"GND";
"A"13;
%"Q_CAP"
"1","(-1150,2400)","2","pure_quanta","I80";
;
PART_NUMBER"CH5104KEB02"
MATERIAL"X6S"
TOLERANCE"10%"
VALUE"1UF"
PACK_TYPE"C0402"
VOLTAGE"25V"
$LOCATION"C542"
CDS_LIB"pure_quanta"
CDS_LOCATION"C542"
$SEC"1"
CDS_SEC"1";
"B"
$PN"2"14;
"A"
$PN"1"7;
%"Q_CAP"
"1","(-1500,2400)","2","pure_quanta","I81";
;
PART_NUMBER"CH4104K1B00"
PACK_TYPE"0402"
VALUE"0.1UF"
VOLTAGE"25V"
TOLERANCE"10%"
MATERIAL"X7R"
$LOCATION"C540"
CDS_LIB"pure_quanta"
CDS_LOCATION"C540"
$SEC"1"
CDS_SEC"1";
"B"
$PN"2"14;
"A"
$PN"1"7;
%"UNIVERSAL_GND"
"1","(-1500,2100)","0","logical_power","I82";
;
CDS_LIB"logical_power"
HDL_POWER"GND";
"A"14;
%"UNIVERSAL_GND"
"1","(3800,0)","0","logical_power","I92";
;
CDS_LIB"logical_power"
HDL_POWER"GND";
"A"15;
%"UNIVERSAL_POWER"
"1","(2900,925)","0","logical_power","I93";
;
HDL_POWER"P3V3_AUX"
CDS_LIB"logical_power";
"A"8;
%"Q_CAP"
"1","(2750,650)","2","pure_quanta","I94";
;
PART_NUMBER"CH4104K1B00"
VALUE"0.1UF"
TOLERANCE"10%"
VOLTAGE"25V"
MATERIAL"X7R"
PACK_TYPE"0402"
$LOCATION"C544"
CDS_LIB"pure_quanta"
CDS_LOCATION"C544"
$SEC"1"
CDS_SEC"1";
"B"
$PN"2"16;
"A"
$PN"1"8;
%"UNIVERSAL_GND"
"1","(2750,450)","0","logical_power","I95";
;
CDS_LIB"logical_power"
HDL_POWER"GND";
"A"16;
%"74LVC1G02GW"
"1","(900,200)","0","pure_quanta","I96";
;
PART_NUMBER"ALVC1G02000"
PACK_TYPE"SMLF"
VALUE"74LVC1G02GW"
MATERIAL"IC"
$LOCATION"U23"
CDS_LIB"pure_quanta"
NEEDS_NO_SIZE"TRUE"
CDS_LOCATION"U23"
$SEC"1"
CDS_SEC"1";
"GND"
$PN"3"10;
"VCC"
$PN"5"9;
"Y"
$PN"4"21;
"A"
$PN"2"27;
"B"
$PN"1"26;
%"Q_RES"
"1","(2075,200)","0","pure_quanta","I97";
;
PART_NUMBER"CS03322FB03"
MATERIAL"CHIP"
PACK_TYPE"0402LF"
TOLERANCE"1%"
VALUE"33.2"
WATTAGE"1/16W"
$LOCATION"R745"
CDS_LIB"pure_quanta"
CDS_LOCATION"R745"
$SEC"1"
CDS_SEC"1";
"B"
$PN"2"18;
"A"
$PN"1"21;
%"UNIVERSAL_POWER"
"1","(900,925)","0","logical_power","I98";
;
HDL_POWER"P3V3_AUX"
CDS_LIB"logical_power";
"A"9;
%"UNIVERSAL_GND"
"1","(750,450)","0","logical_power","I99";
;
CDS_LIB"logical_power"
HDL_POWER"GND";
"A"17;
END.
